M48
INCH,TZ
T01C.000001
T02C.000008
T03C.00001
T04C.000012
T05C.000015
T06C.000016
T07C.000016
T08C.000018
T09C.00002
T010C.00002
T011C.000022
T012C.000024
T013C.000026
T014C.00003
T015C.00003
T016C.000031
T017C.000032
T018C.000034
T019C.000036
T020C.000039
T021C.00004
T022C.000041
T023C.000044
T024C.000045
T025C.000046
T026C.000047
T027C.000049
T028C.00005
T029C.000054
T030C.000059
T031C.000063
T032C.000065
T033C.000084
T034C.000086
T035C.000087
T036C.000096
T037C.000125
T038C.000126
T039C.00015
T040C.000177
T041C.000224
;EXTENTS: -111.225 -115.061 80.824  76.988  
;LEADER: 12 
;HEADER: 
;CODE  : ASCII 
;FILE  : D:/<user>/15126-1b/gerber/15126-1b.rou for board D:/<user>/15126-1b/gerber/#Taaaavl08468.tmp
%
G90
F1
M16
T041
M16
G00X1968670Y208007
G41
M15
G03Y206007A1000
G01X1972670
G03Y208007A1000
G01X1968670
M16
G00Y243440
G41
M15
G03Y241440A1000
G01X1972670
G03Y243440A1000
G01X1968670
M16
G00X1949000Y220186
G41
M15
G03X1951000A1000
G01Y221386
G03X1949000A1000
G01Y220186
M16
G00Y228061
G41
M15
G03X1951000A1000
G01Y229261
G03X1949000A1000
G01Y228061
M16
G00X1950206Y59267
G41
M15
G03Y57267A1000
G01X1955306
G03Y59267A1000
G01X1950206
M16
G00Y-13960
G41
M15
G03Y-15960A1000
G01X1955306
G03Y-13960A1000
G01X1950206
M16
G00X1693300Y451047
G41
M15
G03X1705900A6300
G01Y457547
G03X1693300A6300
G01Y451047
M16
G00Y232150
G41
M15
G03X1705900A6300
G01Y238650
G03X1693300A6300
G01Y232150
M16
G00X1833443Y126457
G41
M15
G03Y113857A6300
G01X1839943
G03Y126457A6300
G01X1833443
M16
G00X1860623Y232150
G41
M15
G03X1873223A6300
G01Y238650
G03X1860623A6300
G01Y232150
M16
G00X1951554Y126457
G41
M15
G03Y113857A6300
G01X1958054
G03Y126457A6300
G01X1951554
M16
G00X1949206Y451047
G41
M15
G03X1961806A6300
G01Y457547
G03X1949206A6300
G01Y451047
M16
G00X385837Y86228
G41
M15
G03X390537A2350
G01Y91128
G03X385837A2350
G01Y86228
M16
G00Y48427
G41
M15
G03X390537A2350
G01Y53327
G03X385837A2350
G01Y48427
M16
G00Y10628
G41
M15
G03X390537A2350
G01Y15528
G03X385837A2350
G01Y10628
M16
G00X1035446Y511629
G41
M15
G03X1040146A2350
G01Y516529
G03X1035446A2350
G01Y511629
M16
G00Y549429
G41
M15
G03X1040146A2350
G01Y554329
G03X1035446A2350
G01Y549429
M16
G00Y587229
G41
M15
G03X1040146A2350
G01Y592129
G03X1035446A2350
G01Y587229
M16
G00X385837Y511629
G41
M15
G03X390537A2350
G01Y516529
G03X385837A2350
G01Y511629
M16
G00Y549429
G41
M15
G03X390537A2350
G01Y554329
G03X385837A2350
G01Y549429
M16
G00Y587229
G41
M15
G03X390537A2350
G01Y592129
G03X385837A2350
G01Y587229
M16
G00X1035446Y48427
G41
M15
G03X1040146A2350
G01Y53327
G03X1035446A2350
G01Y48427
M16
G00Y10628
G41
M15
G03X1040146A2350
G01Y15528
G03X1035446A2350
G01Y10628
M16
G00Y86228
G41
M15
G03X1040146A2350
G01Y91128
G03X1035446A2350
G01Y86228
M16
G00X385837Y568305
G41
M15
G03X390537A2350
G01Y573205
G03X385837A2350
G01Y568305
M16
G00X1035446Y530505
G41
M15
G03X1040146A2350
G01Y535405
G03X1035446A2350
G01Y530505
M16
G00Y568305
G41
M15
G03X1040146A2350
G01Y573205
G03X1035446A2350
G01Y568305
M16
G00Y606105
G41
M15
G03X1040146A2350
G01Y611005
G03X1035446A2350
G01Y606105
M16
G00X385837Y530505
G41
M15
G03X390537A2350
G01Y535405
G03X385837A2350
G01Y530505
M16
G00Y606105
G41
M15
G03X390537A2350
G01Y611005
G03X385837A2350
G01Y606105
M16
G00X1035446Y29527
G41
M15
G03X1040146A2350
G01Y34427
G03X1035446A2350
G01Y29527
M16
G00X385837
G41
M15
G03X390537A2350
G01Y34427
G03X385837A2350
G01Y29527
M16
G00Y-8272
G41
M15
G03X390537A2350
G01Y-3372
G03X385837A2350
G01Y-8272
M16
G00X1035446
G41
M15
G03X1040146A2350
G01Y-3372
G03X1035446A2350
G01Y-8272
M16
G00X385837Y67328
G41
M15
G03X390537A2350
G01Y72228
G03X385837A2350
G01Y67328
M16
G00X1035446
G41
M15
G03X1040146A2350
G01Y72228
G03X1035446A2350
G01Y67328
M16
G00X1926852Y512752
G41
M15
G03Y509652A1550
G01X1932052
G03Y512752A1550
G01X1926852
M16
G00X1884727Y534091
G41
M15
G03Y530991A1550
G01X1889927
G03Y534091A1550
G01X1884727
M16
G00X1886127Y512752
G41
M15
G03Y509652A1550
G01X1888527
G03Y512752A1550
G01X1886127
M16
G00X1928252Y534091
G41
M15
G03Y530991A1550
G01X1930652
G03Y534091A1550
G01X1928252
M16
G40
M30
